(kicad_pcb
	(version 20221018)
	(generator pcbnew)
	(general
    (thickness 1.7403)
  )
	(paper "A4")
	(title_block
    (title "Data Center RDIMM DDR4 Tester")
    (date "2024-09-30")
    (rev "1.2.4")
		(comment 9 "footprints 37-46 of 690")
	)
	(layers
    (0 "F.Cu" signal)
    (1 "In1.Cu" power)
    (2 "In2.Cu" signal)
    (3 "In3.Cu" power)
    (4 "In4.Cu" power)
    (5 "In5.Cu" signal)
    (6 "In6.Cu" power)
    (7 "In7.Cu" signal)
    (8 "In8.Cu" power)
    (9 "In9.Cu" signal)
    (10 "In10.Cu" power)
    (31 "B.Cu" signal)
    (32 "B.Adhes" user "B.Adhesive")
    (33 "F.Adhes" user "F.Adhesive")
    (34 "B.Paste" user)
    (35 "F.Paste" user)
    (36 "B.SilkS" user "B.Silkscreen")
    (37 "F.SilkS" user "F.Silkscreen")
    (38 "B.Mask" user)
    (39 "F.Mask" user)
    (40 "Dwgs.User" user "User.Drawings")
    (41 "Cmts.User" user "User.Comments")
    (42 "Eco1.User" user "User.Eco1")
    (43 "Eco2.User" user "User.Eco2")
    (44 "Edge.Cuts" user)
    (45 "Margin" user)
    (46 "B.CrtYd" user "B.Courtyard")
    (47 "F.CrtYd" user "F.Courtyard")
    (48 "B.Fab" user)
    (49 "F.Fab" user)
  )
	(footprint "data-center-rdimm-ddr4-tester-footprints:R_0402_1005Metric" (layer "F.Cu")
    (at 120.65 110.85 -90)
    (descr "Resistor SMD 0402")
    (tags "resistor SMD 0402")
    (property "Author" "Antmicro")
    (property "License" "Apache-2.0")
    (property "MPN" "CR0402-FX-1003GLF")
    (property "Manufacturer" "Bourns")
    (property "Sheetfile" "supply.kicad_sch")
    (property "Sheetname" "Supply")
    (property "Tolerance" "1%")
    (property "Val" "100k")
    (property "ki_description" "100k resistor in 0402 package with 1% tolerance")
    (attr smd)
    (fp_text reference "R122" (at 2.85 1.8) (layer "F.SilkS")
        (effects (font (size 0.7 0.7) (thickness 0.15)) (justify left bottom))
    )
    (fp_text value "R_100k_0402" (at 0 1.4 -90) (layer "F.Fab") hide
        (effects (font (size 0.7 0.7) (thickness 0.15)) (justify left bottom))
    )
    (fp_text user "Author: Antmicro" (at -0.95 4.169 -90) (layer "F.Fab") hide
        (effects (font (size 0.7 0.7) (thickness 0.15)) (justify left bottom))
    )
    (fp_text user "License: Apache-2.0" (at -0.95 5.169 -90) (layer "F.Fab") hide
        (effects (font (size 0.7 0.7) (thickness 0.15)) (justify left bottom))
    )
    (fp_text user "${REFERENCE}" (at -0.95 3.168 -90) (layer "F.Fab") hide
        (effects (font (size 0.7 0.7) (thickness 0.15)) (justify left bottom))
    )
    (fp_rect (start -0.93 -0.47) (end 0.93 0.47)
      (stroke (width 0.05) (type solid)) (fill none) (layer "F.CrtYd"))
    (fp_rect (start -0.5 -0.25) (end 0.5 0.25)
      (stroke (width 0.15) (type solid)) (fill none) (layer "F.Fab"))
    (pad "1" smd roundrect (at -0.485 0 270) (size 0.59 0.64) (layers "F.Cu" "F.Paste" "F.Mask") (roundrect_rratio 0.25)
      (net 104 "VCC5V0") (pintype "passive"))
    (pad "2" smd roundrect (at 0.485 0 270) (size 0.59 0.64) (layers "F.Cu" "F.Paste" "F.Mask") (roundrect_rratio 0.25)
      (net 536 "/Supply/SYS_PWR_GOOD") (pintype "passive"))
  )
	(footprint "data-center-rdimm-ddr4-tester-footprints:C_0603_1608Metric" (layer "F.Cu")
    (at 116.036328 87.610008 180)
    (descr "Capacitor SMD 0603")
    (tags "capacitor 0603")
    (property "Author" "Antmicro")
    (property "Dielectric" "")
    (property "License" "Apache-2.0")
    (property "MPN" "GRM188R60J226MEA0D")
    (property "Manufacturer" "Murata")
    (property "Sheetfile" "supply.kicad_sch")
    (property "Sheetname" "Supply")
    (property "Val" "22u")
    (property "Voltage" "")
    (property "ki_description" " ")
    (attr smd)
    (fp_text reference "C40" (at 1.656328 12.840008 180) (layer "F.SilkS")
        (effects (font (size 0.7 0.7) (thickness 0.15)) (justify left bottom))
    )
    (fp_text value "C_22u_0603" (at 0 1.6 180) (layer "F.Fab") hide
        (effects (font (size 0.7 0.7) (thickness 0.15)) (justify left bottom))
    )
    (fp_text user "${REFERENCE}" (at -1.682 3.895 180) (layer "F.Fab") hide
        (effects (font (size 0.7 0.7) (thickness 0.15)) (justify left bottom))
    )
    (fp_text user "Author: Antmicro" (at -1.682 4.894 180) (layer "F.Fab") hide
        (effects (font (size 0.7 0.7) (thickness 0.15)) (justify left bottom))
    )
    (fp_text user "License: Apache-2.0" (at -1.682 5.895 180) (layer "F.Fab") hide
        (effects (font (size 0.7 0.7) (thickness 0.15)) (justify left bottom))
    )
    (fp_line (start -0.3 -0.3) (end 0.3 -0.3)
      (stroke (width 0.15) (type solid)) (layer "F.SilkS"))
    (fp_line (start -0.3 0.3) (end 0.3 0.3)
      (stroke (width 0.15) (type solid)) (layer "F.SilkS"))
    (fp_rect (start -1.24 -0.7) (end 1.24 0.7)
      (stroke (width 0.05) (type solid)) (fill none) (layer "F.CrtYd"))
    (fp_rect (start -0.8 -0.4) (end 0.8 0.4)
      (stroke (width 0.15) (type solid)) (fill none) (layer "F.Fab"))
    (pad "1" smd roundrect (at -0.7 0 180) (size 0.6 0.8) (layers "F.Cu" "F.Paste" "F.Mask") (roundrect_rratio 0.2)
      (net 301 "VDD1V2") (pintype "passive"))
    (pad "2" smd roundrect (at 0.7 0 180) (size 0.6 0.8) (layers "F.Cu" "F.Paste" "F.Mask") (roundrect_rratio 0.2)
      (net 9 "GND") (pintype "passive"))
  )
	(footprint "data-center-rdimm-ddr4-tester-footprints:R_0402_1005Metric" (layer "F.Cu")
    (at 119.411328 115.497157)
    (descr "Resistor SMD 0402")
    (tags "resistor SMD 0402")
    (property "Author" "Antmicro")
    (property "License" "Apache-2.0")
    (property "MPN" "CR0402-FX-1692GLF")
    (property "Manufacturer" "Bourns")
    (property "Sheetfile" "supply.kicad_sch")
    (property "Sheetname" "Supply")
    (property "Tolerance" "1%")
    (property "Val" "16k9")
    (property "ki_description" "16k9 resistor in 0402 package with 1% tolerance")
    (attr smd)
    (fp_text reference "R115" (at -4.931328 3.312843) (layer "F.SilkS")
        (effects (font (size 0.7 0.7) (thickness 0.15)) (justify left bottom))
    )
    (fp_text value "R_16k9_0402" (at 0 1.4) (layer "F.Fab") hide
        (effects (font (size 0.7 0.7) (thickness 0.15)) (justify left bottom))
    )
    (fp_text user "${REFERENCE}" (at -0.95 3.168) (layer "F.Fab") hide
        (effects (font (size 0.7 0.7) (thickness 0.15)) (justify left bottom))
    )
    (fp_text user "License: Apache-2.0" (at -0.95 5.169) (layer "F.Fab") hide
        (effects (font (size 0.7 0.7) (thickness 0.15)) (justify left bottom))
    )
    (fp_text user "Author: Antmicro" (at -0.95 4.169) (layer "F.Fab") hide
        (effects (font (size 0.7 0.7) (thickness 0.15)) (justify left bottom))
    )
    (fp_rect (start -0.93 -0.47) (end 0.93 0.47)
      (stroke (width 0.05) (type solid)) (fill none) (layer "F.CrtYd"))
    (fp_rect (start -0.5 -0.25) (end 0.5 0.25)
      (stroke (width 0.15) (type solid)) (fill none) (layer "F.Fab"))
    (pad "1" smd roundrect (at -0.485 0) (size 0.59 0.64) (layers "F.Cu" "F.Paste" "F.Mask") (roundrect_rratio 0.25)
      (net 69 "Net-(IC1-COMP)") (pintype "passive"))
    (pad "2" smd roundrect (at 0.485 0) (size 0.59 0.64) (layers "F.Cu" "F.Paste" "F.Mask") (roundrect_rratio 0.25)
      (net 107 "Net-(C172-Pad1)") (pintype "passive"))
  )
	(footprint "data-center-rdimm-ddr4-tester-footprints:R_0402_1005Metric" (layer "F.Cu")
    (at 121.536328 102.747157 -90)
    (descr "Resistor SMD 0402")
    (tags "resistor SMD 0402")
    (property "Author" "Antmicro")
    (property "License" "Apache-2.0")
    (property "MPN" "CR0402-FX-1003GLF")
    (property "Manufacturer" "Bourns")
    (property "Sheetfile" "supply.kicad_sch")
    (property "Sheetname" "Supply")
    (property "Tolerance" "1%")
    (property "Val" "100k")
    (property "ki_description" "100k resistor in 0402 package with 1% tolerance")
    (attr smd)
    (fp_text reference "R40" (at 1.062843 -1.263672 -90) (layer "F.SilkS")
        (effects (font (size 0.7 0.7) (thickness 0.15)) (justify left bottom))
    )
    (fp_text value "R_100k_0402" (at 0 1.4 -90) (layer "F.Fab") hide
        (effects (font (size 0.7 0.7) (thickness 0.15)) (justify left bottom))
    )
    (fp_text user "Author: Antmicro" (at -0.95 4.169 -90) (layer "F.Fab") hide
        (effects (font (size 0.7 0.7) (thickness 0.15)) (justify left bottom))
    )
    (fp_text user "${REFERENCE}" (at -0.95 3.168 -90) (layer "F.Fab") hide
        (effects (font (size 0.7 0.7) (thickness 0.15)) (justify left bottom))
    )
    (fp_text user "License: Apache-2.0" (at -0.95 5.169 -90) (layer "F.Fab") hide
        (effects (font (size 0.7 0.7) (thickness 0.15)) (justify left bottom))
    )
    (fp_rect (start -0.93 -0.47) (end 0.93 0.47)
      (stroke (width 0.05) (type solid)) (fill none) (layer "F.CrtYd"))
    (fp_rect (start -0.5 -0.25) (end 0.5 0.25)
      (stroke (width 0.15) (type solid)) (fill none) (layer "F.Fab"))
    (pad "1" smd roundrect (at -0.485 0 270) (size 0.59 0.64) (layers "F.Cu" "F.Paste" "F.Mask") (roundrect_rratio 0.25)
      (net 613 "Net-(U2-PGOOD)") (pintype "passive"))
    (pad "2" smd roundrect (at 0.485 0 270) (size 0.59 0.64) (layers "F.Cu" "F.Paste" "F.Mask") (roundrect_rratio 0.25)
      (net 307 "5V0_SYS") (pintype "passive"))
  )
	(footprint "data-center-rdimm-ddr4-tester-footprints:R_0402_1005Metric" (layer "F.Cu")
    (at 148.036328 104.372157)
    (descr "Resistor SMD 0402")
    (tags "resistor SMD 0402")
    (property "Author" "Antmicro")
    (property "License" "Apache-2.0")
    (property "MPN" "CR0402-FX-22R0GLF")
    (property "Manufacturer" "Bourns")
    (property "Sheetfile" "interfaces.kicad_sch")
    (property "Sheetname" "Interfaces")
    (property "Tolerance" "1%")
    (property "Val" "22R")
    (property "ki_description" "22R resistor in 0402 package with 1% tolerance")
    (attr smd)
    (fp_text reference "R4" (at 0.863672 0.367843) (layer "F.SilkS")
        (effects (font (size 0.7 0.7) (thickness 0.15)) (justify left bottom))
    )
    (fp_text value "R_22R_0402" (at 0 1.4) (layer "F.Fab") hide
        (effects (font (size 0.7 0.7) (thickness 0.15)) (justify left bottom))
    )
    (fp_text user "Author: Antmicro" (at -0.95 4.169) (layer "F.Fab") hide
        (effects (font (size 0.7 0.7) (thickness 0.15)) (justify left bottom))
    )
    (fp_text user "${REFERENCE}" (at -0.95 3.168) (layer "F.Fab") hide
        (effects (font (size 0.7 0.7) (thickness 0.15)) (justify left bottom))
    )
    (fp_text user "License: Apache-2.0" (at -0.95 5.169) (layer "F.Fab") hide
        (effects (font (size 0.7 0.7) (thickness 0.15)) (justify left bottom))
    )
    (fp_rect (start -0.93 -0.47) (end 0.93 0.47)
      (stroke (width 0.05) (type solid)) (fill none) (layer "F.CrtYd"))
    (fp_rect (start -0.5 -0.25) (end 0.5 0.25)
      (stroke (width 0.15) (type solid)) (fill none) (layer "F.Fab"))
    (pad "1" smd roundrect (at -0.485 0) (size 0.59 0.64) (layers "F.Cu" "F.Paste" "F.Mask") (roundrect_rratio 0.25)
      (net 588 "Net-(U7-BDBUS3)") (pintype "passive"))
    (pad "2" smd roundrect (at 0.485 0) (size 0.59 0.64) (layers "F.Cu" "F.Paste" "F.Mask") (roundrect_rratio 0.25)
      (net 131 "AUX_JTAG_TMS") (pintype "passive"))
  )
	(footprint "data-center-rdimm-ddr4-tester-footprints:C_0603_1608Metric" (layer "F.Cu")
    (at 124.661328 99.497157 -90)
    (descr "Capacitor SMD 0603")
    (tags "capacitor 0603")
    (property "Author" "Antmicro")
    (property "Dielectric" "")
    (property "License" "Apache-2.0")
    (property "MPN" "0603YC104KAZ2A")
    (property "Manufacturer" "AVX")
    (property "Sheetfile" "supply.kicad_sch")
    (property "Sheetname" "Supply")
    (property "Val" "100n")
    (property "Voltage" "")
    (property "ki_description" " ")
    (attr smd)
    (fp_text reference "C2" (at 2.442843 -0.358672 -90) (layer "F.SilkS")
        (effects (font (size 0.7 0.7) (thickness 0.15)) (justify left bottom))
    )
    (fp_text value "C_100n_0603" (at 0 1.6 -90) (layer "F.Fab") hide
        (effects (font (size 0.7 0.7) (thickness 0.15)) (justify left bottom))
    )
    (fp_text user "${REFERENCE}" (at -1.682 3.895 -90) (layer "F.Fab") hide
        (effects (font (size 0.7 0.7) (thickness 0.15)) (justify left bottom))
    )
    (fp_text user "Author: Antmicro" (at -1.682 4.894 -90) (layer "F.Fab") hide
        (effects (font (size 0.7 0.7) (thickness 0.15)) (justify left bottom))
    )
    (fp_text user "License: Apache-2.0" (at -1.682 5.895 -90) (layer "F.Fab") hide
        (effects (font (size 0.7 0.7) (thickness 0.15)) (justify left bottom))
    )
    (fp_line (start -0.3 -0.3) (end 0.3 -0.3)
      (stroke (width 0.15) (type solid)) (layer "F.SilkS"))
    (fp_line (start -0.3 0.3) (end 0.3 0.3)
      (stroke (width 0.15) (type solid)) (layer "F.SilkS"))
    (fp_rect (start -1.24 -0.7) (end 1.24 0.7)
      (stroke (width 0.05) (type solid)) (fill none) (layer "F.CrtYd"))
    (fp_rect (start -0.8 -0.4) (end 0.8 0.4)
      (stroke (width 0.15) (type solid)) (fill none) (layer "F.Fab"))
    (pad "1" smd roundrect (at -0.7 0 270) (size 0.6 0.8) (layers "F.Cu" "F.Paste" "F.Mask") (roundrect_rratio 0.2)
      (net 307 "5V0_SYS") (pintype "passive"))
    (pad "2" smd roundrect (at 0.7 0 270) (size 0.6 0.8) (layers "F.Cu" "F.Paste" "F.Mask") (roundrect_rratio 0.2)
      (net 9 "GND") (pintype "passive"))
  )
	(footprint "data-center-rdimm-ddr4-tester-footprints:C_0603_1608Metric" (layer "F.Cu")
    (at 126.286328 99.497157 -90)
    (descr "Capacitor SMD 0603")
    (tags "capacitor 0603")
    (property "Author" "Antmicro")
    (property "Dielectric" "")
    (property "License" "Apache-2.0")
    (property "MPN" "0603YD105KAT2A")
    (property "Manufacturer" "Walsin")
    (property "Sheetfile" "supply.kicad_sch")
    (property "Sheetname" "Supply")
    (property "Val" "1u")
    (property "Voltage" "")
    (property "ki_description" " ")
    (attr smd)
    (fp_text reference "C4" (at 2.542843 -0.333672 -90) (layer "F.SilkS")
        (effects (font (size 0.7 0.7) (thickness 0.15)) (justify left bottom))
    )
    (fp_text value "C_1u_0603" (at 0 1.6 -90) (layer "F.Fab") hide
        (effects (font (size 0.7 0.7) (thickness 0.15)) (justify left bottom))
    )
    (fp_text user "Author: Antmicro" (at -1.682 4.894 -90) (layer "F.Fab") hide
        (effects (font (size 0.7 0.7) (thickness 0.15)) (justify left bottom))
    )
    (fp_text user "${REFERENCE}" (at -1.682 3.895 -90) (layer "F.Fab") hide
        (effects (font (size 0.7 0.7) (thickness 0.15)) (justify left bottom))
    )
    (fp_text user "License: Apache-2.0" (at -1.682 5.895 -90) (layer "F.Fab") hide
        (effects (font (size 0.7 0.7) (thickness 0.15)) (justify left bottom))
    )
    (fp_line (start -0.3 -0.3) (end 0.3 -0.3)
      (stroke (width 0.15) (type solid)) (layer "F.SilkS"))
    (fp_line (start -0.3 0.3) (end 0.3 0.3)
      (stroke (width 0.15) (type solid)) (layer "F.SilkS"))
    (fp_rect (start -1.24 -0.7) (end 1.24 0.7)
      (stroke (width 0.05) (type solid)) (fill none) (layer "F.CrtYd"))
    (fp_rect (start -0.8 -0.4) (end 0.8 0.4)
      (stroke (width 0.15) (type solid)) (fill none) (layer "F.Fab"))
    (pad "1" smd roundrect (at -0.7 0 270) (size 0.6 0.8) (layers "F.Cu" "F.Paste" "F.Mask") (roundrect_rratio 0.2)
      (net 307 "5V0_SYS") (pintype "passive"))
    (pad "2" smd roundrect (at 0.7 0 270) (size 0.6 0.8) (layers "F.Cu" "F.Paste" "F.Mask") (roundrect_rratio 0.2)
      (net 9 "GND") (pintype "passive"))
  )
	(footprint "data-center-rdimm-ddr4-tester-footprints:C_0603_1608Metric" (layer "F.Cu")
    (at 128.411328 88.122157 90)
    (descr "Capacitor SMD 0603")
    (tags "capacitor 0603")
    (property "Author" "Antmicro")
    (property "Dielectric" "")
    (property "License" "Apache-2.0")
    (property "MPN" "GRM188R60J226MEA0D")
    (property "Manufacturer" "Murata")
    (property "Sheetfile" "supply.kicad_sch")
    (property "Sheetname" "Supply")
    (property "Val" "22u")
    (property "Voltage" "")
    (property "ki_description" " ")
    (attr smd)
    (fp_text reference "C31" (at 0.942157 0.288672 90) (layer "F.SilkS")
        (effects (font (size 0.7 0.7) (thickness 0.15)) (justify left bottom))
    )
    (fp_text value "C_22u_0603" (at 0 1.6 90) (layer "F.Fab") hide
        (effects (font (size 0.7 0.7) (thickness 0.15)) (justify left bottom))
    )
    (fp_text user "${REFERENCE}" (at -1.682 3.895 90) (layer "F.Fab") hide
        (effects (font (size 0.7 0.7) (thickness 0.15)) (justify left bottom))
    )
    (fp_text user "Author: Antmicro" (at -1.682 4.894 90) (layer "F.Fab") hide
        (effects (font (size 0.7 0.7) (thickness 0.15)) (justify left bottom))
    )
    (fp_text user "License: Apache-2.0" (at -1.682 5.895 90) (layer "F.Fab") hide
        (effects (font (size 0.7 0.7) (thickness 0.15)) (justify left bottom))
    )
    (fp_line (start -0.3 -0.3) (end 0.3 -0.3)
      (stroke (width 0.15) (type solid)) (layer "F.SilkS"))
    (fp_line (start -0.3 0.3) (end 0.3 0.3)
      (stroke (width 0.15) (type solid)) (layer "F.SilkS"))
    (fp_rect (start -1.24 -0.7) (end 1.24 0.7)
      (stroke (width 0.05) (type solid)) (fill none) (layer "F.CrtYd"))
    (fp_rect (start -0.8 -0.4) (end 0.8 0.4)
      (stroke (width 0.15) (type solid)) (fill none) (layer "F.Fab"))
    (pad "1" smd roundrect (at -0.7 0 90) (size 0.6 0.8) (layers "F.Cu" "F.Paste" "F.Mask") (roundrect_rratio 0.2)
      (net 303 "VCC2V5") (pintype "passive"))
    (pad "2" smd roundrect (at 0.7 0 90) (size 0.6 0.8) (layers "F.Cu" "F.Paste" "F.Mask") (roundrect_rratio 0.2)
      (net 9 "GND") (pintype "passive"))
  )
	(footprint "data-center-rdimm-ddr4-tester-footprints:R_0402_1005Metric" (layer "F.Cu")
    (at 148.056328 109.832157)
    (descr "Resistor SMD 0402")
    (tags "resistor SMD 0402")
    (property "Author" "Antmicro")
    (property "License" "Apache-2.0")
    (property "MPN" "CR0402-FX-22R0GLF")
    (property "Manufacturer" "Bourns")
    (property "Sheetfile" "interfaces.kicad_sch")
    (property "Sheetname" "Interfaces")
    (property "Tolerance" "1%")
    (property "Val" "22R")
    (property "ki_description" "22R resistor in 0402 package with 1% tolerance")
    (attr smd)
    (fp_text reference "R25" (at 0.863672 0.367843) (layer "F.SilkS")
        (effects (font (size 0.7 0.7) (thickness 0.15)) (justify left bottom))
    )
    (fp_text value "R_22R_0402" (at 0 1.4) (layer "F.Fab") hide
        (effects (font (size 0.7 0.7) (thickness 0.15)) (justify left bottom))
    )
    (fp_text user "${REFERENCE}" (at -0.95 3.168) (layer "F.Fab") hide
        (effects (font (size 0.7 0.7) (thickness 0.15)) (justify left bottom))
    )
    (fp_text user "Author: Antmicro" (at -0.95 4.169) (layer "F.Fab") hide
        (effects (font (size 0.7 0.7) (thickness 0.15)) (justify left bottom))
    )
    (fp_text user "License: Apache-2.0" (at -0.95 5.169) (layer "F.Fab") hide
        (effects (font (size 0.7 0.7) (thickness 0.15)) (justify left bottom))
    )
    (fp_rect (start -0.93 -0.47) (end 0.93 0.47)
      (stroke (width 0.05) (type solid)) (fill none) (layer "F.CrtYd"))
    (fp_rect (start -0.5 -0.25) (end 0.5 0.25)
      (stroke (width 0.15) (type solid)) (fill none) (layer "F.Fab"))
    (pad "1" smd roundrect (at -0.485 0) (size 0.59 0.64) (layers "F.Cu" "F.Paste" "F.Mask") (roundrect_rratio 0.25)
      (net 598 "Net-(U7-ADBUS3)") (pintype "passive"))
    (pad "2" smd roundrect (at 0.485 0) (size 0.59 0.64) (layers "F.Cu" "F.Paste" "F.Mask") (roundrect_rratio 0.25)
      (net 13 "TMS_JTAG") (pintype "passive"))
  )
	(footprint "data-center-rdimm-ddr4-tester-footprints:R_0402_1005Metric" (layer "F.Cu")
    (at 148.056328 110.907157)
    (descr "Resistor SMD 0402")
    (tags "resistor SMD 0402")
    (property "Author" "Antmicro")
    (property "License" "Apache-2.0")
    (property "MPN" "CR0402-FX-22R0GLF")
    (property "Manufacturer" "Bourns")
    (property "Sheetfile" "interfaces.kicad_sch")
    (property "Sheetname" "Interfaces")
    (property "Tolerance" "1%")
    (property "Val" "22R")
    (property "ki_description" "22R resistor in 0402 package with 1% tolerance")
    (attr smd)
    (fp_text reference "R20" (at 0.863672 0.367843) (layer "F.SilkS")
        (effects (font (size 0.7 0.7) (thickness 0.15)) (justify left bottom))
    )
    (fp_text value "R_22R_0402" (at 0 1.4) (layer "F.Fab") hide
        (effects (font (size 0.7 0.7) (thickness 0.15)) (justify left bottom))
    )
    (fp_text user "Author: Antmicro" (at -0.95 4.169) (layer "F.Fab") hide
        (effects (font (size 0.7 0.7) (thickness 0.15)) (justify left bottom))
    )
    (fp_text user "${REFERENCE}" (at -0.95 3.168) (layer "F.Fab") hide
        (effects (font (size 0.7 0.7) (thickness 0.15)) (justify left bottom))
    )
    (fp_text user "License: Apache-2.0" (at -0.95 5.169) (layer "F.Fab") hide
        (effects (font (size 0.7 0.7) (thickness 0.15)) (justify left bottom))
    )
    (fp_rect (start -0.93 -0.47) (end 0.93 0.47)
      (stroke (width 0.05) (type solid)) (fill none) (layer "F.CrtYd"))
    (fp_rect (start -0.5 -0.25) (end 0.5 0.25)
      (stroke (width 0.15) (type solid)) (fill none) (layer "F.Fab"))
    (pad "1" smd roundrect (at -0.485 0) (size 0.59 0.64) (layers "F.Cu" "F.Paste" "F.Mask") (roundrect_rratio 0.25)
      (net 595 "Net-(U7-ADBUS2)") (pintype "passive"))
    (pad "2" smd roundrect (at 0.485 0) (size 0.59 0.64) (layers "F.Cu" "F.Paste" "F.Mask") (roundrect_rratio 0.25)
      (net 15 "TDO_JTAG") (pintype "passive"))
  )
)
